# T6G (Grand Teton) — schematic netlist excerpt (pin names and nets, part order shuffled) for the footprints in the layout excerpt that follows; sources: Cadence DE-HDL packaged netlist, KiCad conversion of 04192023_DAF0TMB3IC0_F0TG_MB_C_brd_V02_OCP.brd

PC477_C0P0_1  Q_CAP  2.2UF 10V 10% X6S  pkg C0402  page 194 : A = PVDDCR_CPU0_P0_PVCC ; B = GND
C1864  Q_CAP  0.1UF 25V 10% X7R  pkg 0402  page 111 : A = P3V3_AUX ; B = GND

(kicad_pcb
	(version 20260206)
	(generator "pcbnew")
	(generator_version "10.0")
	(general
		(thickness 1.6)
		(legacy_teardrops no)
	)
	(paper "A4")
	(title_block
		(title "04192023_DAF0TMB3IC0_F0TG_MB_C_brd_V02_OCP.brd")
		(comment 1 "Grand Teton / footprints 672-673 of 8354")
	)
	(layers
		(0 "F.Cu" signal "TOP")
		(4 "In1.Cu" signal "GND")
		(6 "In2.Cu" signal "IN1")
		(8 "In3.Cu" signal "GND1")
		(10 "In4.Cu" signal "IN2")
		(12 "In5.Cu" signal "GND2")
		(14 "In6.Cu" signal "IN3")
		(16 "In7.Cu" signal "GND3")
		(18 "In8.Cu" signal "VCC")
		(20 "In9.Cu" signal "VCC1")
		(22 "In10.Cu" signal "GND4")
		(24 "In11.Cu" signal "IN4")
		(26 "In12.Cu" signal "GND5")
		(28 "In13.Cu" signal "IN5")
		(30 "In14.Cu" signal "GND6")
		(32 "In15.Cu" signal "IN6")
		(34 "In16.Cu" signal "GND7")
		(2 "B.Cu" signal "BOTTOM")
		(9 "F.Adhes" user "F.Adhesive")
		(11 "B.Adhes" user "B.Adhesive")
		(13 "F.Paste" user "Package Geometry/Pastemask Top")
		(15 "B.Paste" user "Package Geometry/Pastemask Bottom")
		(5 "F.SilkS" user "Ref Des/Silkscreen Top")
		(7 "B.SilkS" user "Ref Des/Silkscreen Bottom")
		(1 "F.Mask" user "Board Geometry/Soldermask Top")
		(3 "B.Mask" user "Board Geometry/Soldermask Bottom")
		(17 "Dwgs.User" user "User.Drawings")
		(19 "Cmts.User" user "User.Comments")
		(21 "Eco1.User" user "User.Eco1")
		(23 "Eco2.User" user "User.Eco2")
		(25 "Edge.Cuts" user "Board Geometry/Outline")
		(27 "Margin" user)
		(31 "F.CrtYd" user "Package Geometry/Place Bound Top")
		(29 "B.CrtYd" user "Package Geometry/Place Bound Bottom")
		(35 "F.Fab" user "Ref Des/Assembly Top")
		(33 "B.Fab" user "Ref Des/Assembly Bottom")
	)
	(footprint ""
		(layer "F.Cu")
		(at 36.919662 -427.377098)
		(property "Reference" "C1864"
			(at 0 0 0)
			(layer "F.SilkS")
			(hide yes)
			(effects
				(font
					(size 1.27 1.27)
				)
			)
		)
		(property "Value" ""
			(at 0 0 0)
			(layer "F.Fab")
			(effects
				(font
					(size 1.27 1.27)
				)
			)
		)
		(duplicate_pad_numbers_are_jumpers no)
		(fp_line
			(start -0.7874 -0.4064)
			(end 0.7874 -0.4064)
			(stroke
				(width 0.1524)
				(type default)
			)
			(layer "F.SilkS")
		)
		(fp_line
			(start -0.7874 0.4064)
			(end -0.7874 -0.4064)
			(stroke
				(width 0.1524)
				(type default)
			)
			(layer "F.SilkS")
		)
		(fp_line
			(start 0.7874 -0.4064)
			(end 0.7874 0.4064)
			(stroke
				(width 0.1524)
				(type default)
			)
			(layer "F.SilkS")
		)
		(fp_line
			(start 0.7874 0.4064)
			(end -0.7874 0.4064)
			(stroke
				(width 0.1524)
				(type default)
			)
			(layer "F.SilkS")
		)
		(fp_line
			(start -0.67945 -0.305054)
			(end -0.12065 -0.305054)
			(stroke
				(width 0.1)
				(type default)
			)
			(layer "F.Fab")
		)
		(fp_line
			(start -0.67945 0.3048)
			(end -0.67945 -0.305054)
			(stroke
				(width 0.1)
				(type default)
			)
			(layer "F.Fab")
		)
		(fp_line
			(start -0.12065 -0.305054)
			(end -0.12065 -0.2794)
			(stroke
				(width 0.1)
				(type default)
			)
			(layer "F.Fab")
		)
		(fp_line
			(start -0.12065 -0.2794)
			(end 0.12065 -0.2794)
			(stroke
				(width 0.1)
				(type default)
			)
			(layer "F.Fab")
		)
		(fp_line
			(start -0.12065 0.2794)
			(end -0.12065 0.3048)
			(stroke
				(width 0.1)
				(type default)
			)
			(layer "F.Fab")
		)
		(fp_line
			(start -0.12065 0.3048)
			(end -0.67945 0.3048)
			(stroke
				(width 0.1)
				(type default)
			)
			(layer "F.Fab")
		)
		(fp_line
			(start 0.120396 0.2794)
			(end -0.12065 0.2794)
			(stroke
				(width 0.1)
				(type default)
			)
			(layer "F.Fab")
		)
		(fp_line
			(start 0.120396 0.3048)
			(end 0.120396 0.2794)
			(stroke
				(width 0.1)
				(type default)
			)
			(layer "F.Fab")
		)
		(fp_line
			(start 0.12065 -0.3048)
			(end 0.67945 -0.3048)
			(stroke
				(width 0.1)
				(type default)
			)
			(layer "F.Fab")
		)
		(fp_line
			(start 0.12065 -0.2794)
			(end 0.12065 -0.3048)
			(stroke
				(width 0.1)
				(type default)
			)
			(layer "F.Fab")
		)
		(fp_line
			(start 0.67945 -0.3048)
			(end 0.67945 0.3048)
			(stroke
				(width 0.1)
				(type default)
			)
			(layer "F.Fab")
		)
		(fp_line
			(start 0.67945 0.3048)
			(end 0.120396 0.3048)
			(stroke
				(width 0.1)
				(type default)
			)
			(layer "F.Fab")
		)
		(pad "1" smd circle
			(at -0.40005 0)
			(size 0 0)
			(layers "F.Cu" "F.Mask" "F.Paste")
			(net "P3V3_AUX")
		)
		(pad "2" smd circle
			(at 0.40005 0)
			(size 0 0)
			(layers "F.Cu" "F.Mask" "F.Paste")
			(net "GND")
		)
	)
	(footprint ""
		(layer "F.Cu")
		(at 367.996978 -177.773076 90)
		(property "Reference" "PC477_C0P0_1"
			(at 0 0 90)
			(layer "F.SilkS")
			(hide yes)
			(effects
				(font
					(size 1.27 1.27)
				)
			)
		)
		(property "Value" ""
			(at 0 0 90)
			(layer "F.Fab")
			(effects
				(font
					(size 1.27 1.27)
				)
			)
		)
		(duplicate_pad_numbers_are_jumpers no)
		(fp_line
			(start 0.7874 -0.4064)
			(end 0.7874 0.4064)
			(stroke
				(width 0.1524)
				(type default)
			)
			(layer "F.SilkS")
		)
		(fp_line
			(start -0.7874 -0.4064)
			(end 0.7874 -0.4064)
			(stroke
				(width 0.1524)
				(type default)
			)
			(layer "F.SilkS")
		)
		(fp_line
			(start 0.7874 0.4064)
			(end -0.7874 0.4064)
			(stroke
				(width 0.1524)
				(type default)
			)
			(layer "F.SilkS")
		)
		(fp_line
			(start -0.7874 0.4064)
			(end -0.7874 -0.4064)
			(stroke
				(width 0.1524)
				(type default)
			)
			(layer "F.SilkS")
		)
		(fp_line
			(start -0.12065 -0.305054)
			(end -0.12065 -0.2794)
			(stroke
				(width 0.1)
				(type default)
			)
			(layer "F.Fab")
		)
		(fp_line
			(start -0.67945 -0.305054)
			(end -0.12065 -0.305054)
			(stroke
				(width 0.1)
				(type default)
			)
			(layer "F.Fab")
		)
		(fp_line
			(start 0.67945 -0.3048)
			(end 0.67945 0.3048)
			(stroke
				(width 0.1)
				(type default)
			)
			(layer "F.Fab")
		)
		(fp_line
			(start 0.12065 -0.3048)
			(end 0.67945 -0.3048)
			(stroke
				(width 0.1)
				(type default)
			)
			(layer "F.Fab")
		)
		(fp_line
			(start 0.12065 -0.2794)
			(end 0.12065 -0.3048)
			(stroke
				(width 0.1)
				(type default)
			)
			(layer "F.Fab")
		)
		(fp_line
			(start -0.12065 -0.2794)
			(end 0.12065 -0.2794)
			(stroke
				(width 0.1)
				(type default)
			)
			(layer "F.Fab")
		)
		(fp_line
			(start 0.120396 0.2794)
			(end -0.12065 0.2794)
			(stroke
				(width 0.1)
				(type default)
			)
			(layer "F.Fab")
		)
		(fp_line
			(start -0.12065 0.2794)
			(end -0.12065 0.3048)
			(stroke
				(width 0.1)
				(type default)
			)
			(layer "F.Fab")
		)
		(fp_line
			(start 0.67945 0.3048)
			(end 0.120396 0.3048)
			(stroke
				(width 0.1)
				(type default)
			)
			(layer "F.Fab")
		)
		(fp_line
			(start 0.120396 0.3048)
			(end 0.120396 0.2794)
			(stroke
				(width 0.1)
				(type default)
			)
			(layer "F.Fab")
		)
		(fp_line
			(start -0.12065 0.3048)
			(end -0.67945 0.3048)
			(stroke
				(width 0.1)
				(type default)
			)
			(layer "F.Fab")
		)
		(fp_line
			(start -0.67945 0.3048)
			(end -0.67945 -0.305054)
			(stroke
				(width 0.1)
				(type default)
			)
			(layer "F.Fab")
		)
		(pad "1" smd circle
			(at -0.40005 0 90)
			(size 0 0)
			(layers "F.Cu" "F.Mask" "F.Paste")
			(net "PVDDCR_CPU0_P0_PVCC")
		)
		(pad "2" smd circle
			(at 0.40005 0 90)
			(size 0 0)
			(layers "F.Cu" "F.Mask" "F.Paste")
			(net "GND")
		)
	)
)
